FILE_TYPE=LIBRARY_PARTS;
TIME=' COMPILATION ON MON JUL 05 19:34:44 2010  ';
PRIMITIVE 'MOSFET_N';
  PIN
    'GATE':
      PIN_NUMBER='(G)';
      INPUT_LOAD='(-0.01,0.01)';
    'DRAIN':
      PIN_NUMBER='(D)';
      OUTPUT_LOAD='(1.0,-1.0)';
    'SOURCE':
      PIN_NUMBER='(S)';
      INPUT_LOAD='(-0.01,0.01)';
      OUTPUT_LOAD='(1.0,-1.0)';
      BIDIRECTIONAL='TRUE';
  END_PIN;
  BODY
    PHYS_DES_PREFIX='U';
    CLASS='IC';
    PART_NAME='MOSFET_N';
    BODY_NAME='mosfet_n';
  END_BODY;
END_PRIMITIVE;
END.
